# BASEBOARD_FAB2 (Tioga Pass) — schematic netlist excerpt (pin names and nets, part order shuffled) for the footprints in the layout excerpt that follows; sources: Cadence DE-HDL packaged netlist, KiCad conversion of Wiwynn_Tioga_Pass_MB.brd

C5D34  CAP_A  22.0UF 4V 20% X6S  pkg 0603V  page 42 : A = PVCCMCP_CPU0 ; B = GND
C2D40  CAP_A  22.0UF 4V 20% X6S  pkg 0603V  page 76 : A = PVCCMCP_CPU1 ; B = GND
R1D13  RES  90.9K 1% CHIP  pkg 0402  page 199 : A = A_HSC_ISET_S ; B = A_HSC_ISET

(kicad_pcb
	(version 20260206)
	(generator "pcbnew")
	(generator_version "10.0")
	(general
		(thickness 1.6)
		(legacy_teardrops no)
	)
	(paper "A4")
	(title_block
		(title "Wiwynn_Tioga_Pass_MB.brd")
		(comment 1 "Tioga Pass / footprints 1957-1959 of 4770")
	)
	(layers
		(0 "F.Cu" signal "TOP")
		(4 "In1.Cu" signal "L2GND")
		(6 "In2.Cu" signal "L3")
		(8 "In3.Cu" signal "L4GND")
		(10 "In4.Cu" signal "L5")
		(12 "In5.Cu" signal "L6GND")
		(14 "In6.Cu" signal "L7VCC")
		(16 "In7.Cu" signal "L8VCC")
		(18 "In8.Cu" signal "L9GND")
		(20 "In9.Cu" signal "L10")
		(22 "In10.Cu" signal "L11GND")
		(24 "In11.Cu" signal "L12")
		(26 "In12.Cu" signal "L13GND")
		(2 "B.Cu" signal "BOTTOM")
		(9 "F.Adhes" user "F.Adhesive")
		(11 "B.Adhes" user "B.Adhesive")
		(13 "F.Paste" user "Package Geometry/Pastemask Top")
		(15 "B.Paste" user "Package Geometry/Pastemask Bottom")
		(5 "F.SilkS" user "Ref Des/Silkscreen Top")
		(7 "B.SilkS" user "Ref Des/Silkscreen Bottom")
		(1 "F.Mask" user "Board Geometry/Soldermask Top")
		(3 "B.Mask" user "Board Geometry/Soldermask Bottom")
		(17 "Dwgs.User" user "User.Drawings")
		(19 "Cmts.User" user "User.Comments")
		(21 "Eco1.User" user "User.Eco1")
		(23 "Eco2.User" user "User.Eco2")
		(25 "Edge.Cuts" user "Board Geometry/Outline")
		(27 "Margin" user)
		(31 "F.CrtYd" user "Package Geometry/Place Bound Top")
		(29 "B.CrtYd" user "Package Geometry/Place Bound Bottom")
		(35 "F.Fab" user "Ref Des/Assembly Top")
		(33 "B.Fab" user "Ref Des/Assembly Bottom")
	)
	(footprint ""
		(layer "F.Cu")
		(at 19.2024 -84.3534)
		(property "Reference" "R1D13"
			(at 0 0 0)
			(layer "F.SilkS")
			(hide yes)
			(effects
				(font
					(size 1.27 1.27)
				)
			)
		)
		(property "Value" ""
			(at 0 0 0)
			(layer "F.Fab")
			(effects
				(font
					(size 1.27 1.27)
				)
			)
		)
		(duplicate_pad_numbers_are_jumpers no)
		(fp_poly
			(pts
				(xy -0.2794 -0.1016) (xy 0.2794 -0.1016) (xy 0.2794 0.9906) (xy -0.2794 0.9906)
			)
			(stroke
				(width 0)
				(type default)
			)
			(fill no)
			(layer "F.CrtYd")
		)
		(fp_line
			(start -0.2794 -0.1016)
			(end -0.2794 0.9906)
			(stroke
				(width 0.1)
				(type default)
			)
			(layer "F.Fab")
		)
		(fp_line
			(start -0.2794 0.9906)
			(end 0.2794 0.9906)
			(stroke
				(width 0.1)
				(type default)
			)
			(layer "F.Fab")
		)
		(fp_line
			(start 0.2794 -0.1016)
			(end -0.2794 -0.1016)
			(stroke
				(width 0.1)
				(type default)
			)
			(layer "F.Fab")
		)
		(fp_line
			(start 0.2794 0.9906)
			(end 0.2794 -0.1016)
			(stroke
				(width 0.1)
				(type default)
			)
			(layer "F.Fab")
		)
		(pad "1" smd rect
			(at 0 0)
			(size 0.508 0.508)
			(layers "F.Cu" "F.Mask" "F.Paste")
			(net "A_HSC_ISET_S")
		)
		(pad "2" smd rect
			(at 0 0.889)
			(size 0.508 0.508)
			(layers "F.Cu" "F.Mask" "F.Paste")
			(net "A_HSC_ISET")
		)
		(zone
			(layer "F.Cu")
			(hatch none 0.5)
			(connect_pads
				(clearance 0)
			)
			(min_thickness 0.25)
			(keepout
				(tracks allowed)
				(vias not_allowed)
				(pads allowed)
				(copperpour not_allowed)
				(footprints allowed)
			)
			(placement
				(enabled no)
				(sheetname "")
			)
			(fill
				(thermal_gap 0.5)
				(thermal_bridge_width 0.5)
				(island_removal_mode 0)
			)
			(polygon
				(pts
					(xy 18.9484 -84.0994) (xy 19.4564 -84.0994) (xy 19.4564 -83.7184) (xy 18.9484 -83.7184)
				)
			)
		)
		(zone
			(layer "F.Cu")
			(hatch none 0.5)
			(connect_pads
				(clearance 0)
			)
			(min_thickness 0.25)
			(keepout
				(tracks not_allowed)
				(vias allowed)
				(pads allowed)
				(copperpour not_allowed)
				(footprints allowed)
			)
			(placement
				(enabled no)
				(sheetname "")
			)
			(fill
				(thermal_gap 0.5)
				(thermal_bridge_width 0.5)
				(island_removal_mode 0)
			)
			(polygon
				(pts
					(xy 18.9484 -83.7184) (xy 19.4564 -83.7184) (xy 19.4564 -84.0994) (xy 18.9484 -84.0994)
				)
			)
		)
	)
	(footprint ""
		(layer "F.Cu")
		(at 105.62844 -73.279)
		(property "Reference" "C2D40"
			(at 0 0 0)
			(layer "F.SilkS")
			(hide yes)
			(effects
				(font
					(size 1.27 1.27)
				)
			)
		)
		(property "Value" ""
			(at 0 0 0)
			(layer "F.Fab")
			(effects
				(font
					(size 1.27 1.27)
				)
			)
		)
		(duplicate_pad_numbers_are_jumpers no)
		(fp_poly
			(pts
				(xy -0.4953 -0.2032) (xy 0.4953 -0.2032) (xy 0.4953 1.6002) (xy -0.4953 1.6002)
			)
			(stroke
				(width 0)
				(type default)
			)
			(fill no)
			(layer "F.CrtYd")
		)
		(fp_line
			(start -0.4953 -0.2032)
			(end 0.4953 -0.2032)
			(stroke
				(width 0.1)
				(type default)
			)
			(layer "F.Fab")
		)
		(fp_line
			(start -0.4953 1.6002)
			(end -0.4953 -0.2032)
			(stroke
				(width 0.1)
				(type default)
			)
			(layer "F.Fab")
		)
		(fp_line
			(start 0.4953 -0.2032)
			(end 0.4953 1.6002)
			(stroke
				(width 0.1)
				(type default)
			)
			(layer "F.Fab")
		)
		(fp_line
			(start 0.4953 1.6002)
			(end -0.4953 1.6002)
			(stroke
				(width 0.1)
				(type default)
			)
			(layer "F.Fab")
		)
		(pad "1" smd rect
			(at 0 0)
			(size 0.762 0.889)
			(layers "F.Cu" "F.Mask" "F.Paste")
			(net "PVCCMCP_CPU1")
		)
		(pad "2" smd rect
			(at 0 1.397)
			(size 0.762 0.889)
			(layers "F.Cu" "F.Mask" "F.Paste")
			(net "GND")
		)
		(zone
			(layer "F.Cu")
			(hatch none 0.5)
			(connect_pads
				(clearance 0)
			)
			(min_thickness 0.25)
			(keepout
				(tracks not_allowed)
				(vias allowed)
				(pads allowed)
				(copperpour not_allowed)
				(footprints allowed)
			)
			(placement
				(enabled no)
				(sheetname "")
			)
			(fill
				(thermal_gap 0.5)
				(thermal_bridge_width 0.5)
				(island_removal_mode 0)
			)
			(polygon
				(pts
					(xy 105.24744 -72.8345) (xy 106.00944 -72.8345) (xy 106.00944 -72.3265) (xy 105.24744 -72.3265)
				)
			)
		)
	)
	(footprint ""
		(layer "F.Cu")
		(at 270.654272 -77.636116)
		(property "Reference" "C5D34"
			(at 0 0 0)
			(layer "F.SilkS")
			(hide yes)
			(effects
				(font
					(size 1.27 1.27)
				)
			)
		)
		(property "Value" ""
			(at 0 0 0)
			(layer "F.Fab")
			(effects
				(font
					(size 1.27 1.27)
				)
			)
		)
		(duplicate_pad_numbers_are_jumpers no)
		(fp_poly
			(pts
				(xy -0.4953 -0.2032) (xy 0.4953 -0.2032) (xy 0.4953 1.6002) (xy -0.4953 1.6002)
			)
			(stroke
				(width 0)
				(type default)
			)
			(fill no)
			(layer "F.CrtYd")
		)
		(fp_line
			(start -0.4953 -0.2032)
			(end 0.4953 -0.2032)
			(stroke
				(width 0.1)
				(type default)
			)
			(layer "F.Fab")
		)
		(fp_line
			(start -0.4953 1.6002)
			(end -0.4953 -0.2032)
			(stroke
				(width 0.1)
				(type default)
			)
			(layer "F.Fab")
		)
		(fp_line
			(start 0.4953 -0.2032)
			(end 0.4953 1.6002)
			(stroke
				(width 0.1)
				(type default)
			)
			(layer "F.Fab")
		)
		(fp_line
			(start 0.4953 1.6002)
			(end -0.4953 1.6002)
			(stroke
				(width 0.1)
				(type default)
			)
			(layer "F.Fab")
		)
		(pad "1" smd rect
			(at 0 0)
			(size 0.762 0.889)
			(layers "F.Cu" "F.Mask" "F.Paste")
			(net "PVCCMCP_CPU0")
		)
		(pad "2" smd rect
			(at 0 1.397)
			(size 0.762 0.889)
			(layers "F.Cu" "F.Mask" "F.Paste")
			(net "GND")
		)
		(zone
			(layer "F.Cu")
			(hatch none 0.5)
			(connect_pads
				(clearance 0)
			)
			(min_thickness 0.25)
			(keepout
				(tracks not_allowed)
				(vias allowed)
				(pads allowed)
				(copperpour not_allowed)
				(footprints allowed)
			)
			(placement
				(enabled no)
				(sheetname "")
			)
			(fill
				(thermal_gap 0.5)
				(thermal_bridge_width 0.5)
				(island_removal_mode 0)
			)
			(polygon
				(pts
					(xy 270.273272 -77.191616) (xy 271.035272 -77.191616) (xy 271.035272 -76.683616) (xy 270.273272 -76.683616)
				)
			)
		)
	)
)
